# T6G (Grand Teton) — schematic netlist excerpt (pin names and nets, part order shuffled) for the footprints in the layout excerpt that follows; sources: Cadence DE-HDL packaged netlist, KiCad conversion of 04192023_DAF0TMB3IC0_F0TG_MB_C_brd_V02_OCP.brd

R1077  Q_RES  4.7K 5% EMPTY  pkg 0201LF  page 298 : A = P1V8_CPU0_RT_1D ; B = TEST2_RT_CPU0_P2
PC482_2  Q_CAP  0.1UF 25V 10% X7R  pkg 0402  page 194 : A = SW_P12V_AUX_PVDDCR_CPU0_P0_FLT ; B = GND
R4548  Q_RES  100K 1% CHIP  pkg 0402LF  page 124 : A = SWB_HSC_EN ; B = GND

(kicad_pcb
	(version 20260206)
	(generator "pcbnew")
	(generator_version "10.0")
	(general
		(thickness 1.6)
		(legacy_teardrops no)
	)
	(paper "A4")
	(title_block
		(title "04192023_DAF0TMB3IC0_F0TG_MB_C_brd_V02_OCP.brd")
		(comment 1 "Grand Teton / footprints 2726-2728 of 8354")
	)
	(layers
		(0 "F.Cu" signal "TOP")
		(4 "In1.Cu" signal "GND")
		(6 "In2.Cu" signal "IN1")
		(8 "In3.Cu" signal "GND1")
		(10 "In4.Cu" signal "IN2")
		(12 "In5.Cu" signal "GND2")
		(14 "In6.Cu" signal "IN3")
		(16 "In7.Cu" signal "GND3")
		(18 "In8.Cu" signal "VCC")
		(20 "In9.Cu" signal "VCC1")
		(22 "In10.Cu" signal "GND4")
		(24 "In11.Cu" signal "IN4")
		(26 "In12.Cu" signal "GND5")
		(28 "In13.Cu" signal "IN5")
		(30 "In14.Cu" signal "GND6")
		(32 "In15.Cu" signal "IN6")
		(34 "In16.Cu" signal "GND7")
		(2 "B.Cu" signal "BOTTOM")
		(9 "F.Adhes" user "F.Adhesive")
		(11 "B.Adhes" user "B.Adhesive")
		(13 "F.Paste" user "Package Geometry/Pastemask Top")
		(15 "B.Paste" user "Package Geometry/Pastemask Bottom")
		(5 "F.SilkS" user "Ref Des/Silkscreen Top")
		(7 "B.SilkS" user "Ref Des/Silkscreen Bottom")
		(1 "F.Mask" user "Board Geometry/Soldermask Top")
		(3 "B.Mask" user "Board Geometry/Soldermask Bottom")
		(17 "Dwgs.User" user "User.Drawings")
		(19 "Cmts.User" user "User.Comments")
		(21 "Eco1.User" user "User.Eco1")
		(23 "Eco2.User" user "User.Eco2")
		(25 "Edge.Cuts" user "Board Geometry/Outline")
		(27 "Margin" user)
		(31 "F.CrtYd" user "Package Geometry/Place Bound Top")
		(29 "B.CrtYd" user "Package Geometry/Place Bound Bottom")
		(35 "F.Fab" user "Ref Des/Assembly Top")
		(33 "B.Fab" user "Ref Des/Assembly Bottom")
	)
	(footprint ""
		(layer "F.Cu")
		(at 371.794278 -176.59731)
		(property "Reference" "PC482_2"
			(at 0 0 0)
			(layer "F.SilkS")
			(hide yes)
			(effects
				(font
					(size 1.27 1.27)
				)
			)
		)
		(property "Value" ""
			(at 0 0 0)
			(layer "F.Fab")
			(effects
				(font
					(size 1.27 1.27)
				)
			)
		)
		(duplicate_pad_numbers_are_jumpers no)
		(fp_line
			(start -0.7874 -0.4064)
			(end 0.7874 -0.4064)
			(stroke
				(width 0.1524)
				(type default)
			)
			(layer "F.SilkS")
		)
		(fp_line
			(start -0.7874 0.4064)
			(end -0.7874 -0.4064)
			(stroke
				(width 0.1524)
				(type default)
			)
			(layer "F.SilkS")
		)
		(fp_line
			(start 0.7874 -0.4064)
			(end 0.7874 0.4064)
			(stroke
				(width 0.1524)
				(type default)
			)
			(layer "F.SilkS")
		)
		(fp_line
			(start 0.7874 0.4064)
			(end -0.7874 0.4064)
			(stroke
				(width 0.1524)
				(type default)
			)
			(layer "F.SilkS")
		)
		(fp_line
			(start -0.67945 -0.305054)
			(end -0.12065 -0.305054)
			(stroke
				(width 0.1)
				(type default)
			)
			(layer "F.Fab")
		)
		(fp_line
			(start -0.67945 0.3048)
			(end -0.67945 -0.305054)
			(stroke
				(width 0.1)
				(type default)
			)
			(layer "F.Fab")
		)
		(fp_line
			(start -0.12065 -0.305054)
			(end -0.12065 -0.2794)
			(stroke
				(width 0.1)
				(type default)
			)
			(layer "F.Fab")
		)
		(fp_line
			(start -0.12065 -0.2794)
			(end 0.12065 -0.2794)
			(stroke
				(width 0.1)
				(type default)
			)
			(layer "F.Fab")
		)
		(fp_line
			(start -0.12065 0.2794)
			(end -0.12065 0.3048)
			(stroke
				(width 0.1)
				(type default)
			)
			(layer "F.Fab")
		)
		(fp_line
			(start -0.12065 0.3048)
			(end -0.67945 0.3048)
			(stroke
				(width 0.1)
				(type default)
			)
			(layer "F.Fab")
		)
		(fp_line
			(start 0.120396 0.2794)
			(end -0.12065 0.2794)
			(stroke
				(width 0.1)
				(type default)
			)
			(layer "F.Fab")
		)
		(fp_line
			(start 0.120396 0.3048)
			(end 0.120396 0.2794)
			(stroke
				(width 0.1)
				(type default)
			)
			(layer "F.Fab")
		)
		(fp_line
			(start 0.12065 -0.3048)
			(end 0.67945 -0.3048)
			(stroke
				(width 0.1)
				(type default)
			)
			(layer "F.Fab")
		)
		(fp_line
			(start 0.12065 -0.2794)
			(end 0.12065 -0.3048)
			(stroke
				(width 0.1)
				(type default)
			)
			(layer "F.Fab")
		)
		(fp_line
			(start 0.67945 -0.3048)
			(end 0.67945 0.3048)
			(stroke
				(width 0.1)
				(type default)
			)
			(layer "F.Fab")
		)
		(fp_line
			(start 0.67945 0.3048)
			(end 0.120396 0.3048)
			(stroke
				(width 0.1)
				(type default)
			)
			(layer "F.Fab")
		)
		(pad "1" smd circle
			(at -0.40005 0)
			(size 0 0)
			(layers "F.Cu" "F.Mask" "F.Paste")
			(net "SW_P12V_AUX_PVDDCR_CPU0_P0_FLT")
		)
		(pad "2" smd circle
			(at 0.40005 0)
			(size 0 0)
			(layers "F.Cu" "F.Mask" "F.Paste")
			(net "GND")
		)
	)
	(footprint ""
		(layer "F.Cu")
		(at 352.705416 -438.992772 180)
		(property "Reference" "R4548"
			(at 0 0 180)
			(layer "F.SilkS")
			(hide yes)
			(effects
				(font
					(size 1.27 1.27)
				)
			)
		)
		(property "Value" ""
			(at 0 0 180)
			(layer "F.Fab")
			(effects
				(font
					(size 1.27 1.27)
				)
			)
		)
		(duplicate_pad_numbers_are_jumpers no)
		(fp_line
			(start 0.7874 0.4064)
			(end -0.7874 0.4064)
			(stroke
				(width 0.1524)
				(type default)
			)
			(layer "F.SilkS")
		)
		(fp_line
			(start 0.7874 -0.4064)
			(end 0.7874 0.4064)
			(stroke
				(width 0.1524)
				(type default)
			)
			(layer "F.SilkS")
		)
		(fp_line
			(start -0.7874 0.4064)
			(end -0.7874 -0.4064)
			(stroke
				(width 0.1524)
				(type default)
			)
			(layer "F.SilkS")
		)
		(fp_line
			(start -0.7874 -0.4064)
			(end 0.7874 -0.4064)
			(stroke
				(width 0.1524)
				(type default)
			)
			(layer "F.SilkS")
		)
		(fp_line
			(start 0.67945 0.3048)
			(end 0.120396 0.3048)
			(stroke
				(width 0.1)
				(type default)
			)
			(layer "F.Fab")
		)
		(fp_line
			(start 0.67945 -0.3048)
			(end 0.67945 0.3048)
			(stroke
				(width 0.1)
				(type default)
			)
			(layer "F.Fab")
		)
		(fp_line
			(start 0.12065 -0.2794)
			(end 0.12065 -0.3048)
			(stroke
				(width 0.1)
				(type default)
			)
			(layer "F.Fab")
		)
		(fp_line
			(start 0.12065 -0.3048)
			(end 0.67945 -0.3048)
			(stroke
				(width 0.1)
				(type default)
			)
			(layer "F.Fab")
		)
		(fp_line
			(start 0.120396 0.3048)
			(end 0.120396 0.2794)
			(stroke
				(width 0.1)
				(type default)
			)
			(layer "F.Fab")
		)
		(fp_line
			(start 0.120396 0.2794)
			(end -0.12065 0.2794)
			(stroke
				(width 0.1)
				(type default)
			)
			(layer "F.Fab")
		)
		(fp_line
			(start -0.12065 0.3048)
			(end -0.67945 0.3048)
			(stroke
				(width 0.1)
				(type default)
			)
			(layer "F.Fab")
		)
		(fp_line
			(start -0.12065 0.2794)
			(end -0.12065 0.3048)
			(stroke
				(width 0.1)
				(type default)
			)
			(layer "F.Fab")
		)
		(fp_line
			(start -0.12065 -0.2794)
			(end 0.12065 -0.2794)
			(stroke
				(width 0.1)
				(type default)
			)
			(layer "F.Fab")
		)
		(fp_line
			(start -0.12065 -0.305054)
			(end -0.12065 -0.2794)
			(stroke
				(width 0.1)
				(type default)
			)
			(layer "F.Fab")
		)
		(fp_line
			(start -0.67945 0.3048)
			(end -0.67945 -0.305054)
			(stroke
				(width 0.1)
				(type default)
			)
			(layer "F.Fab")
		)
		(fp_line
			(start -0.67945 -0.305054)
			(end -0.12065 -0.305054)
			(stroke
				(width 0.1)
				(type default)
			)
			(layer "F.Fab")
		)
		(pad "1" smd circle
			(at -0.40005 0 180)
			(size 0 0)
			(layers "F.Cu" "F.Mask" "F.Paste")
			(net "SWB_HSC_EN")
		)
		(pad "2" smd circle
			(at 0.40005 0 180)
			(size 0 0)
			(layers "F.Cu" "F.Mask" "F.Paste")
			(net "GND")
		)
	)
	(footprint ""
		(layer "F.Cu")
		(at 397.369538 -392.1252)
		(property "Reference" "R1077"
			(at 0 0 0)
			(layer "F.SilkS")
			(hide yes)
			(effects
				(font
					(size 1.27 1.27)
				)
			)
		)
		(property "Value" ""
			(at 0 0 0)
			(layer "F.Fab")
			(effects
				(font
					(size 1.27 1.27)
				)
			)
		)
		(duplicate_pad_numbers_are_jumpers no)
		(fp_line
			(start -0.32512 -0.175006)
			(end 0.32512 -0.175006)
			(stroke
				(width 0.1)
				(type default)
			)
			(layer "F.Fab")
		)
		(fp_line
			(start -0.32512 0.175006)
			(end -0.32512 -0.175006)
			(stroke
				(width 0.1)
				(type default)
			)
			(layer "F.Fab")
		)
		(fp_line
			(start 0.32512 -0.175006)
			(end 0.32512 0.175006)
			(stroke
				(width 0.1)
				(type default)
			)
			(layer "F.Fab")
		)
		(fp_line
			(start 0.32512 0.175006)
			(end -0.32512 0.175006)
			(stroke
				(width 0.1)
				(type default)
			)
			(layer "F.Fab")
		)
		(pad "1" smd rect
			(at -0.2667 0)
			(size 0.3048 0.381)
			(layers "F.Cu" "F.Mask" "F.Paste")
			(net "P1V8_CPU0_RT_1D")
		)
		(pad "2" smd rect
			(at 0.2667 0 180)
			(size 0.3048 0.381)
			(layers "F.Cu" "F.Mask" "F.Paste")
			(net "TEST2_RT_CPU0_P2")
		)
	)
)
